(kicad_pcb
	(version 20241229)
	(generator "pcbnew")
	(generator_version "9.0")
	(general
		(thickness 1.6296)
		(legacy_teardrops no)
	)
	(paper "A3")
	(title_block
		(title "Thunderbolt to 10GbE adapter")
		(date "2026-04-21")
		(rev "1.1.0")
		(company "Antmicro Ltd")
		(comment 1 "www.antmicro.com")
		(comment 9 "footprints 602-606 of 703")
	)
	(layers
		(0 "F.Cu" signal)
		(4 "In1.Cu" signal)
		(6 "In2.Cu" signal)
		(8 "In3.Cu" signal)
		(10 "In4.Cu" signal)
		(12 "In5.Cu" signal)
		(14 "In6.Cu" signal)
		(2 "B.Cu" signal)
		(9 "F.Adhes" user "F.Adhesive")
		(11 "B.Adhes" user "B.Adhesive")
		(13 "F.Paste" user)
		(15 "B.Paste" user)
		(5 "F.SilkS" user "F.Silkscreen")
		(7 "B.SilkS" user "B.Silkscreen")
		(1 "F.Mask" user)
		(3 "B.Mask" user)
		(17 "Dwgs.User" user "User.Drawings")
		(19 "Cmts.User" user "User.Comments")
		(21 "Eco1.User" user "User.Eco1")
		(23 "Eco2.User" user "User.Eco2")
		(25 "Edge.Cuts" user)
		(27 "Margin" user)
		(31 "F.CrtYd" user "F.Courtyard")
		(29 "B.CrtYd" user "B.Courtyard")
		(35 "F.Fab" user)
		(33 "B.Fab" user)
	)
	(footprint "antmicro-footprints:C_0402_1005Metric"
		(layer "B.Cu")
		(at 127.800001 142.3 -90)
		(descr "Capacitor SMD 0402")
		(tags "capacitor SMD 0402")
		(property "Reference" "C29"
			(at -1.15 -2.45 90)
			(layer "B.SilkS")
			(effects
				(font
					(size 0.7 0.7)
					(thickness 0.15)
				)
				(justify left bottom mirror)
			)
		)
		(property "Value" "C_220p_0402"
			(at -1.022927 -2.155213 90)
			(layer "B.Fab")
			(effects
				(font
					(size 0.7 0.7)
					(thickness 0.15)
				)
				(justify left bottom mirror)
			)
		)
		(property "Datasheet" "https://spicat.kyocera-avx.com/product/mlcc/chartview/04025C221JAT2A/"
			(at 0 0 90)
			(layer "B.Fab")
			(hide yes)
			(effects
				(font
					(size 1.27 1.27)
					(thickness 0.15)
				)
				(justify mirror)
			)
		)
		(property "Description" "SMD Multilayer Ceramic Capacitor, 220 pF, 50 V, 0402 [1005 Metric], ± 10%, X7R, MC"
			(at 0 0 90)
			(layer "B.Fab")
			(hide yes)
			(effects
				(font
					(size 1.27 1.27)
					(thickness 0.15)
				)
				(justify mirror)
			)
		)
		(property "MPN" "04025C221JAT2A"
			(at 0 0 270)
			(unlocked yes)
			(layer "B.Fab")
			(hide yes)
			(effects
				(font
					(size 1 1)
					(thickness 0.15)
				)
				(justify mirror)
			)
		)
		(property "Manufacturer" "KYOCERA AVX"
			(at 0 0 270)
			(unlocked yes)
			(layer "B.Fab")
			(hide yes)
			(effects
				(font
					(size 1 1)
					(thickness 0.15)
				)
				(justify mirror)
			)
		)
		(property "License" "Apache-2.0"
			(at 0 0 270)
			(unlocked yes)
			(layer "B.Fab")
			(hide yes)
			(effects
				(font
					(size 1 1)
					(thickness 0.15)
				)
				(justify mirror)
			)
		)
		(property "Val" "220p"
			(at 0 0 270)
			(unlocked yes)
			(layer "B.Fab")
			(hide yes)
			(effects
				(font
					(size 1 1)
					(thickness 0.15)
				)
				(justify mirror)
			)
		)
		(property "Voltage" ""
			(at 0 0 270)
			(unlocked yes)
			(layer "B.Fab")
			(hide yes)
			(effects
				(font
					(size 1 1)
					(thickness 0.15)
				)
				(justify mirror)
			)
		)
		(property "Dielectric" ""
			(at 0 0 270)
			(unlocked yes)
			(layer "B.Fab")
			(hide yes)
			(effects
				(font
					(size 1 1)
					(thickness 0.15)
				)
				(justify mirror)
			)
		)
		(property "Author" "Antmicro"
			(at 0 0 270)
			(unlocked yes)
			(layer "B.Fab")
			(hide yes)
			(effects
				(font
					(size 1 1)
					(thickness 0.15)
				)
				(justify mirror)
			)
		)
		(sheetname "/PD and TB DC-DC/")
		(sheetfile "PD_and_TB_DC_DC.kicad_sch")
		(attr smd)
		(fp_rect
			(start -0.925 0.47)
			(end 0.925 -0.47)
			(stroke
				(width 0.05)
				(type default)
			)
			(fill no)
			(layer "B.CrtYd")
		)
		(fp_line
			(start -0.494 0.25)
			(end 0.504 0.25)
			(stroke
				(width 0.15)
				(type solid)
			)
			(layer "B.Fab")
		)
		(fp_line
			(start 0.504 0.25)
			(end 0.504 -0.248)
			(stroke
				(width 0.15)
				(type solid)
			)
			(layer "B.Fab")
		)
		(fp_line
			(start -0.494 -0.248)
			(end -0.494 0.25)
			(stroke
				(width 0.15)
				(type solid)
			)
			(layer "B.Fab")
		)
		(fp_line
			(start 0.504 -0.248)
			(end -0.494 -0.248)
			(stroke
				(width 0.15)
				(type solid)
			)
			(layer "B.Fab")
		)
		(fp_text user "License: Apache-2.0"
			(at -0.939 -5.799 90)
			(layer "B.Fab")
			(effects
				(font
					(size 0.7 0.7)
					(thickness 0.15)
				)
				(justify left bottom mirror)
			)
		)
		(fp_text user "Author: Antmicro"
			(at -0.939 -3.399 90)
			(layer "B.Fab")
			(effects
				(font
					(size 0.7 0.7)
					(thickness 0.15)
				)
				(justify left bottom mirror)
			)
		)
		(fp_text user "${REFERENCE}"
			(at -0.939 -4.599 90)
			(layer "B.Fab")
			(effects
				(font
					(size 0.7 0.7)
					(thickness 0.15)
				)
				(justify left bottom mirror)
			)
		)
		(pad "1" smd roundrect
			(at -0.48 0 270)
			(size 0.59 0.64)
			(layers "B.Cu" "B.Mask" "B.Paste")
			(roundrect_rratio 0.25)
			(net 23 "GND")
			(pintype "passive")
		)
		(pad "2" smd roundrect
			(at 0.48 0 270)
			(size 0.59 0.64)
			(layers "B.Cu" "B.Mask" "B.Paste")
			(roundrect_rratio 0.25)
			(net 305 "/PD and TB DC-DC/USB3.CC2")
			(pintype "passive")
		)
	)
	(footprint "antmicro-footprints:R_0402_1005Metric"
		(layer "B.Cu")
		(at 150.131866 70.035117 90)
		(descr "Resistor SMD 0402")
		(tags "resistor SMD 0402")
		(property "Reference" "R199"
			(at -9.464883 19.468134 270)
			(layer "B.SilkS")
			(effects
				(font
					(size 0.7 0.7)
					(thickness 0.15)
				)
				(justify mirror)
			)
		)
		(property "Value" "R_3k3_0402"
			(at -1.011843 -1.772047 270)
			(layer "B.Fab")
			(effects
				(font
					(size 0.7 0.7)
					(thickness 0.15)
				)
				(justify left bottom mirror)
			)
		)
		(property "Datasheet" "https://www.bourns.com/docs/product-datasheets/cr.pdf"
			(at 0 0 270)
			(layer "B.Fab")
			(hide yes)
			(effects
				(font
					(size 1.27 1.27)
					(thickness 0.15)
				)
				(justify mirror)
			)
		)
		(property "Description" "SMD Chip Resistor, 3.3 kohm, ± 1%, 63 mW, 0402 [1005 Metric], Thick Film, General Purpose"
			(at 0 0 270)
			(layer "B.Fab")
			(hide yes)
			(effects
				(font
					(size 1.27 1.27)
					(thickness 0.15)
				)
				(justify mirror)
			)
		)
		(property "MPN" "CR0402-FX-3301GLF"
			(at 0 0 90)
			(unlocked yes)
			(layer "B.Fab")
			(hide yes)
			(effects
				(font
					(size 1 1)
					(thickness 0.15)
				)
				(justify mirror)
			)
		)
		(property "Manufacturer" "Bourns"
			(at 0 0 90)
			(unlocked yes)
			(layer "B.Fab")
			(hide yes)
			(effects
				(font
					(size 1 1)
					(thickness 0.15)
				)
				(justify mirror)
			)
		)
		(property "License" "Apache-2.0"
			(at 0 0 90)
			(unlocked yes)
			(layer "B.Fab")
			(hide yes)
			(effects
				(font
					(size 1 1)
					(thickness 0.15)
				)
				(justify mirror)
			)
		)
		(property "Author" "Antmicro"
			(at 0 0 90)
			(unlocked yes)
			(layer "B.Fab")
			(hide yes)
			(effects
				(font
					(size 1 1)
					(thickness 0.15)
				)
				(justify mirror)
			)
		)
		(property "Val" "3k3"
			(at 0 0 90)
			(unlocked yes)
			(layer "B.Fab")
			(hide yes)
			(effects
				(font
					(size 1 1)
					(thickness 0.15)
				)
				(justify mirror)
			)
		)
		(property "Tolerance" "1%"
			(at 0 0 90)
			(unlocked yes)
			(layer "B.Fab")
			(hide yes)
			(effects
				(font
					(size 1 1)
					(thickness 0.15)
				)
				(justify mirror)
			)
		)
		(sheetname "/X710-AT2 10GbE/")
		(sheetfile "x710-at2-10gbe.kicad_sch")
		(attr smd)
		(fp_rect
			(start -0.925 0.47)
			(end 0.925 -0.47)
			(stroke
				(width 0.05)
				(type default)
			)
			(fill no)
			(layer "B.CrtYd")
		)
		(fp_rect
			(start -0.5 0.25)
			(end 0.5 -0.25)
			(stroke
				(width 0.15)
				(type solid)
			)
			(fill no)
			(layer "B.Fab")
		)
		(fp_text user "License: Apache-2.0"
			(at -0.95 -5.169 270)
			(layer "B.Fab")
			(effects
				(font
					(size 0.7 0.7)
					(thickness 0.15)
				)
				(justify left bottom mirror)
			)
		)
		(fp_text user "Author: Antmicro"
			(at -0.95 -4.169 270)
			(layer "B.Fab")
			(effects
				(font
					(size 0.7 0.7)
					(thickness 0.15)
				)
				(justify left bottom mirror)
			)
		)
		(fp_text user "${REFERENCE}"
			(at -0.95 -3.168 270)
			(layer "B.Fab")
			(effects
				(font
					(size 0.7 0.7)
					(thickness 0.15)
				)
				(justify left bottom mirror)
			)
		)
		(pad "1" smd roundrect
			(at -0.48 0 90)
			(size 0.59 0.64)
			(layers "B.Cu" "B.Mask" "B.Paste")
			(roundrect_rratio 0.25)
			(net 78 "/X710-AT2 10GbE/MDIO1_SDA1")
			(pintype "passive")
		)
		(pad "2" smd roundrect
			(at 0.48 0 90)
			(size 0.59 0.64)
			(layers "B.Cu" "B.Mask" "B.Paste")
			(roundrect_rratio 0.25)
			(net 7 "+3V3")
			(pintype "passive")
		)
	)
	(footprint "antmicro-footprints:R_0402_1005Metric"
		(layer "B.Cu")
		(at 145.031866 73.260117)
		(descr "Resistor SMD 0402")
		(tags "resistor SMD 0402")
		(property "Reference" "R123"
			(at 18.468134 7.539883 180)
			(layer "B.SilkS")
			(effects
				(font
					(size 0.7 0.7)
					(thickness 0.15)
				)
				(justify mirror)
			)
		)
		(property "Value" "R_100R_0402"
			(at -1.011843 -1.772047 180)
			(layer "B.Fab")
			(effects
				(font
					(size 0.7 0.7)
					(thickness 0.15)
				)
				(justify left bottom mirror)
			)
		)
		(property "Datasheet" "https://www.bourns.com/docs/product-datasheets/cr.pdf"
			(at 0 0 180)
			(layer "B.Fab")
			(hide yes)
			(effects
				(font
					(size 1.27 1.27)
					(thickness 0.15)
				)
				(justify mirror)
			)
		)
		(property "Description" "SMD Chip Resistor, 100 ohm, ± 1%, 62.5 mW, 0402 [1005 Metric], Thick Film, General Purpose"
			(at 0 0 180)
			(layer "B.Fab")
			(hide yes)
			(effects
				(font
					(size 1.27 1.27)
					(thickness 0.15)
				)
				(justify mirror)
			)
		)
		(property "MPN" "CR0402-FX-1000GLF"
			(at 0 0 0)
			(unlocked yes)
			(layer "B.Fab")
			(hide yes)
			(effects
				(font
					(size 1 1)
					(thickness 0.15)
				)
				(justify mirror)
			)
		)
		(property "Manufacturer" "Bourns"
			(at 0 0 0)
			(unlocked yes)
			(layer "B.Fab")
			(hide yes)
			(effects
				(font
					(size 1 1)
					(thickness 0.15)
				)
				(justify mirror)
			)
		)
		(property "License" "Apache-2.0"
			(at 0 0 0)
			(unlocked yes)
			(layer "B.Fab")
			(hide yes)
			(effects
				(font
					(size 1 1)
					(thickness 0.15)
				)
				(justify mirror)
			)
		)
		(property "Author" "Antmicro"
			(at 0 0 0)
			(unlocked yes)
			(layer "B.Fab")
			(hide yes)
			(effects
				(font
					(size 1 1)
					(thickness 0.15)
				)
				(justify mirror)
			)
		)
		(property "Val" "100R"
			(at 0 0 0)
			(unlocked yes)
			(layer "B.Fab")
			(hide yes)
			(effects
				(font
					(size 1 1)
					(thickness 0.15)
				)
				(justify mirror)
			)
		)
		(property "Tolerance" "1%"
			(at 0 0 0)
			(unlocked yes)
			(layer "B.Fab")
			(hide yes)
			(effects
				(font
					(size 1 1)
					(thickness 0.15)
				)
				(justify mirror)
			)
		)
		(sheetname "/X710-AT2 RSVD/")
		(sheetfile "x710-at2-rsvd.kicad_sch")
		(attr smd)
		(fp_rect
			(start -0.925 0.47)
			(end 0.925 -0.47)
			(stroke
				(width 0.05)
				(type default)
			)
			(fill no)
			(layer "B.CrtYd")
		)
		(fp_rect
			(start -0.5 0.25)
			(end 0.5 -0.25)
			(stroke
				(width 0.15)
				(type solid)
			)
			(fill no)
			(layer "B.Fab")
		)
		(fp_text user "Author: Antmicro"
			(at -0.95 -4.169 180)
			(layer "B.Fab")
			(effects
				(font
					(size 0.7 0.7)
					(thickness 0.15)
				)
				(justify left bottom mirror)
			)
		)
		(fp_text user "License: Apache-2.0"
			(at -0.95 -5.169 180)
			(layer "B.Fab")
			(effects
				(font
					(size 0.7 0.7)
					(thickness 0.15)
				)
				(justify left bottom mirror)
			)
		)
		(fp_text user "${REFERENCE}"
			(at -0.95 -3.168 180)
			(layer "B.Fab")
			(effects
				(font
					(size 0.7 0.7)
					(thickness 0.15)
				)
				(justify left bottom mirror)
			)
		)
		(pad "1" smd roundrect
			(at -0.48 0)
			(size 0.59 0.64)
			(layers "B.Cu" "B.Mask" "B.Paste")
			(roundrect_rratio 0.25)
			(net 23 "GND")
			(pintype "passive")
		)
		(pad "2" smd roundrect
			(at 0.48 0)
			(size 0.59 0.64)
			(layers "B.Cu" "B.Mask" "B.Paste")
			(roundrect_rratio 0.25)
			(net 94 "/X710-AT2 RSVD/RSVDW5_VSS")
			(pintype "passive")
		)
	)
	(footprint "antmicro-footprints:R_0402_1005Metric"
		(layer "B.Cu")
		(at 161 69.5 90)
		(descr "Resistor SMD 0402")
		(tags "resistor SMD 0402")
		(property "Reference" "R198"
			(at -2.25 0 270)
			(layer "B.SilkS")
			(effects
				(font
					(size 0.7 0.7)
					(thickness 0.15)
				)
				(justify mirror)
			)
		)
		(property "Value" "R_0R_0402"
			(at -1.011843 -1.772047 270)
			(layer "B.Fab")
			(effects
				(font
					(size 0.7 0.7)
					(thickness 0.15)
				)
				(justify left bottom mirror)
			)
		)
		(property "Datasheet" "https://industrial.panasonic.com/cdbs/www-data/pdf/RDA0000/AOA0000C301.pdf"
			(at 0 0 270)
			(layer "B.Fab")
			(hide yes)
			(effects
				(font
					(size 1.27 1.27)
					(thickness 0.15)
				)
				(justify mirror)
			)
		)
		(property "Description" "SMD Chip Resistor, Jumper, 0 ohm, 100 mW, 0402 [1005 Metric], Thick Film, General Purpose"
			(at 0 0 270)
			(layer "B.Fab")
			(hide yes)
			(effects
				(font
					(size 1.27 1.27)
					(thickness 0.15)
				)
				(justify mirror)
			)
		)
		(property "MPN" "ERJ2GE0R00X"
			(at 0 0 90)
			(unlocked yes)
			(layer "B.Fab")
			(hide yes)
			(effects
				(font
					(size 1 1)
					(thickness 0.15)
				)
				(justify mirror)
			)
		)
		(property "Manufacturer" "Panasonic"
			(at 0 0 90)
			(unlocked yes)
			(layer "B.Fab")
			(hide yes)
			(effects
				(font
					(size 1 1)
					(thickness 0.15)
				)
				(justify mirror)
			)
		)
		(property "License" "Apache-2.0"
			(at 0 0 90)
			(unlocked yes)
			(layer "B.Fab")
			(hide yes)
			(effects
				(font
					(size 1 1)
					(thickness 0.15)
				)
				(justify mirror)
			)
		)
		(property "Author" "Antmicro"
			(at 0 0 90)
			(unlocked yes)
			(layer "B.Fab")
			(hide yes)
			(effects
				(font
					(size 1 1)
					(thickness 0.15)
				)
				(justify mirror)
			)
		)
		(property "Val" "0R"
			(at 0 0 90)
			(unlocked yes)
			(layer "B.Fab")
			(hide yes)
			(effects
				(font
					(size 1 1)
					(thickness 0.15)
				)
				(justify mirror)
			)
		)
		(property "Tolerance" "~"
			(at 0 0 90)
			(unlocked yes)
			(layer "B.Fab")
			(hide yes)
			(effects
				(font
					(size 1 1)
					(thickness 0.15)
				)
				(justify mirror)
			)
		)
		(property "Current" "1A"
			(at 0 0 90)
			(unlocked yes)
			(layer "B.Fab")
			(hide yes)
			(effects
				(font
					(size 1 1)
					(thickness 0.15)
				)
				(justify mirror)
			)
		)
		(sheetname "/X710-AT2 10GbE/")
		(sheetfile "x710-at2-10gbe.kicad_sch")
		(attr smd)
		(fp_rect
			(start -0.925 0.47)
			(end 0.925 -0.47)
			(stroke
				(width 0.05)
				(type default)
			)
			(fill no)
			(layer "B.CrtYd")
		)
		(fp_rect
			(start -0.5 0.25)
			(end 0.5 -0.25)
			(stroke
				(width 0.15)
				(type solid)
			)
			(fill no)
			(layer "B.Fab")
		)
		(fp_text user "Author: Antmicro"
			(at -0.95 -4.169 270)
			(layer "B.Fab")
			(effects
				(font
					(size 0.7 0.7)
					(thickness 0.15)
				)
				(justify left bottom mirror)
			)
		)
		(fp_text user "${REFERENCE}"
			(at -0.95 -3.168 270)
			(layer "B.Fab")
			(effects
				(font
					(size 0.7 0.7)
					(thickness 0.15)
				)
				(justify left bottom mirror)
			)
		)
		(fp_text user "License: Apache-2.0"
			(at -0.95 -5.169 270)
			(layer "B.Fab")
			(effects
				(font
					(size 0.7 0.7)
					(thickness 0.15)
				)
				(justify left bottom mirror)
			)
		)
		(pad "1" smd roundrect
			(at -0.48 0 90)
			(size 0.59 0.64)
			(layers "B.Cu" "B.Mask" "B.Paste")
			(roundrect_rratio 0.25)
			(net 124 "/X710-AT2 10GbE/~{P1_INT}")
			(pintype "passive")
		)
		(pad "2" smd roundrect
			(at 0.48 0 90)
			(size 0.59 0.64)
			(layers "B.Cu" "B.Mask" "B.Paste")
			(roundrect_rratio 0.25)
			(net 123 "/X710-AT2 10GbE/~{P1_INT_R}")
			(pintype "passive")
		)
	)
	(footprint "antmicro-footprints:TP_SMD_0.75mm"
		(layer "B.Cu")
		(at 158.681865 78.760117 180)
		(property "Reference" "TP32"
			(at -20.778136 -8.839883 0)
			(layer "B.SilkS")
			(effects
				(font
					(size 0.7 0.7)
					(thickness 0.15)
				)
				(justify mirror)
			)
		)
		(property "Value" "TP_0.75mm_SMD"
			(at 0 -1.2 0)
			(layer "B.Fab")
			(effects
				(font
					(size 0.7 0.7)
					(thickness 0.15)
				)
				(justify left bottom mirror)
			)
		)
		(property "Description" "SMT test point"
			(at 0 0 0)
			(layer "B.Fab")
			(hide yes)
			(effects
				(font
					(size 1.27 1.27)
					(thickness 0.15)
				)
				(justify mirror)
			)
		)
		(property "MPN" ""
			(at 0 0 180)
			(unlocked yes)
			(layer "B.Fab")
			(hide yes)
			(effects
				(font
					(size 1 1)
					(thickness 0.15)
				)
				(justify mirror)
			)
		)
		(property "Manufacturer" ""
			(at 0 0 180)
			(unlocked yes)
			(layer "B.Fab")
			(hide yes)
			(effects
				(font
					(size 1 1)
					(thickness 0.15)
				)
				(justify mirror)
			)
		)
		(property "Author" "Antmicro"
			(at 0 0 180)
			(unlocked yes)
			(layer "B.Fab")
			(hide yes)
			(effects
				(font
					(size 1 1)
					(thickness 0.15)
				)
				(justify mirror)
			)
		)
		(property "License" "Apache-2.0"
			(at 0 0 180)
			(unlocked yes)
			(layer "B.Fab")
			(hide yes)
			(effects
				(font
					(size 1 1)
					(thickness 0.15)
				)
				(justify mirror)
			)
		)
		(sheetname "/X710-AT2 Misc/")
		(sheetfile "x710-at2-mics.kicad_sch")
		(attr exclude_from_pos_files exclude_from_bom)
		(fp_circle
			(center 0 0)
			(end 0.475 0)
			(stroke
				(width 0.05)
				(type default)
			)
			(fill no)
			(layer "B.CrtYd")
		)
		(fp_text user "License: Apache-2.0"
			(at -0.4 -5.101 0)
			(layer "B.Fab")
			(effects
				(font
					(size 0.7 0.7)
					(thickness 0.15)
				)
				(justify left bottom mirror)
			)
		)
		(fp_text user "Author: Antmicro"
			(at -0.4 -3.901 0)
			(layer "B.Fab")
			(effects
				(font
					(size 0.7 0.7)
					(thickness 0.15)
				)
				(justify left bottom mirror)
			)
		)
		(fp_text user "${REFERENCE}"
			(at -0.4 -2.7 0)
			(layer "B.Fab")
			(effects
				(font
					(size 0.7 0.7)
					(thickness 0.15)
				)
				(justify left bottom mirror)
			)
		)
		(pad "1" smd circle
			(at 0 0 180)
			(size 0.75 0.75)
			(layers "B.Cu" "B.Mask")
			(net 105 "/X710-AT2 Misc/PHY_TMS")
			(pinfunction "1")
			(pintype "passive")
		)
	)
)
